# S9S_MB_2U (Grand Teton) — schematic netlist excerpt (pin names and nets, part order shuffled) for the footprints in the layout excerpt that follows; sources: Cadence DE-HDL packaged netlist, KiCad conversion of 03242023_DA0F0TMBIJ0_F0T_Motherboard_J_brd_V01_OCP.brd

PR226  Q_RES  2.2 1% CHIP  pkg 0402LF  page 289 : A = PVCCFA_EHV_FIVRA_CPU1_PVCC1 ; B = PVCCFA_EHV_FIVRA_CPU1_VDD1
R2663  Q_RES  33.2 1% CHIP  pkg 0402LF  page 213 : A = FM_SWB_PWRGD_ISO ; B = FM_SWB_PWRGD_ISO_R

(kicad_pcb
	(version 20260206)
	(generator "pcbnew")
	(generator_version "10.0")
	(general
		(thickness 1.6)
		(legacy_teardrops no)
	)
	(paper "A4")
	(title_block
		(title "03242023_DA0F0TMBIJ0_F0T_Motherboard_J_brd_V01_OCP.brd")
		(comment 1 "Grand Teton / footprints 5639-5640 of 6105")
	)
	(layers
		(0 "F.Cu" signal "TOP")
		(4 "In1.Cu" signal "GND")
		(6 "In2.Cu" signal "IN1")
		(8 "In3.Cu" signal "GND1")
		(10 "In4.Cu" signal "IN2")
		(12 "In5.Cu" signal "GND2")
		(14 "In6.Cu" signal "IN3")
		(16 "In7.Cu" signal "GND3")
		(18 "In8.Cu" signal "VCC")
		(20 "In9.Cu" signal "VCC1")
		(22 "In10.Cu" signal "GND4")
		(24 "In11.Cu" signal "IN4")
		(26 "In12.Cu" signal "GND5")
		(28 "In13.Cu" signal "IN5")
		(30 "In14.Cu" signal "GND6")
		(32 "In15.Cu" signal "IN6")
		(34 "In16.Cu" signal "GND7")
		(2 "B.Cu" signal "BOTTOM")
		(9 "F.Adhes" user "F.Adhesive")
		(11 "B.Adhes" user "B.Adhesive")
		(13 "F.Paste" user "Package Geometry/Pastemask Top")
		(15 "B.Paste" user "Package Geometry/Pastemask Bottom")
		(5 "F.SilkS" user "Ref Des/Silkscreen Top")
		(7 "B.SilkS" user "Ref Des/Silkscreen Bottom")
		(1 "F.Mask" user "Board Geometry/Soldermask Top")
		(3 "B.Mask" user "Board Geometry/Soldermask Bottom")
		(17 "Dwgs.User" user "User.Drawings")
		(19 "Cmts.User" user "User.Comments")
		(21 "Eco1.User" user "User.Eco1")
		(23 "Eco2.User" user "User.Eco2")
		(25 "Edge.Cuts" user "Board Geometry/Outline")
		(27 "Margin" user)
		(31 "F.CrtYd" user "Package Geometry/Place Bound Top")
		(29 "B.CrtYd" user "Package Geometry/Place Bound Bottom")
		(35 "F.Fab" user "Ref Des/Assembly Top")
		(33 "B.Fab" user "Ref Des/Assembly Bottom")
	)
	(footprint ""
		(layer "B.Cu")
		(at 164.64788 -105.755948 180)
		(property "Reference" "R2663"
			(at 0 0 0)
			(layer "B.SilkS")
			(hide yes)
			(effects
				(font
					(size 1.27 1.27)
				)
				(justify mirror)
			)
		)
		(property "Value" ""
			(at 0 0 0)
			(layer "B.Fab")
			(effects
				(font
					(size 1.27 1.27)
				)
				(justify mirror)
			)
		)
		(duplicate_pad_numbers_are_jumpers no)
		(fp_line
			(start 0.7874 0.4064)
			(end 0.7874 -0.4064)
			(stroke
				(width 0.1524)
				(type default)
			)
			(layer "B.SilkS")
		)
		(fp_line
			(start 0.7874 -0.4064)
			(end -0.7874 -0.4064)
			(stroke
				(width 0.1524)
				(type default)
			)
			(layer "B.SilkS")
		)
		(fp_line
			(start -0.7874 0.4064)
			(end 0.7874 0.4064)
			(stroke
				(width 0.1524)
				(type default)
			)
			(layer "B.SilkS")
		)
		(fp_line
			(start -0.7874 -0.4064)
			(end -0.7874 0.4064)
			(stroke
				(width 0.1524)
				(type default)
			)
			(layer "B.SilkS")
		)
		(fp_line
			(start 0.67945 0.3048)
			(end 0.67945 -0.305054)
			(stroke
				(width 0.1)
				(type default)
			)
			(layer "B.Fab")
		)
		(fp_line
			(start 0.67945 -0.305054)
			(end 0.12065 -0.305054)
			(stroke
				(width 0.1)
				(type default)
			)
			(layer "B.Fab")
		)
		(fp_line
			(start 0.12065 0.3048)
			(end 0.67945 0.3048)
			(stroke
				(width 0.1)
				(type default)
			)
			(layer "B.Fab")
		)
		(fp_line
			(start 0.12065 0.2794)
			(end 0.12065 0.3048)
			(stroke
				(width 0.1)
				(type default)
			)
			(layer "B.Fab")
		)
		(fp_line
			(start 0.12065 -0.2794)
			(end -0.12065 -0.2794)
			(stroke
				(width 0.1)
				(type default)
			)
			(layer "B.Fab")
		)
		(fp_line
			(start 0.12065 -0.305054)
			(end 0.12065 -0.2794)
			(stroke
				(width 0.1)
				(type default)
			)
			(layer "B.Fab")
		)
		(fp_line
			(start -0.120396 0.3048)
			(end -0.120396 0.2794)
			(stroke
				(width 0.1)
				(type default)
			)
			(layer "B.Fab")
		)
		(fp_line
			(start -0.120396 0.2794)
			(end 0.12065 0.2794)
			(stroke
				(width 0.1)
				(type default)
			)
			(layer "B.Fab")
		)
		(fp_line
			(start -0.12065 -0.2794)
			(end -0.12065 -0.3048)
			(stroke
				(width 0.1)
				(type default)
			)
			(layer "B.Fab")
		)
		(fp_line
			(start -0.12065 -0.3048)
			(end -0.67945 -0.3048)
			(stroke
				(width 0.1)
				(type default)
			)
			(layer "B.Fab")
		)
		(fp_line
			(start -0.67945 0.3048)
			(end -0.120396 0.3048)
			(stroke
				(width 0.1)
				(type default)
			)
			(layer "B.Fab")
		)
		(fp_line
			(start -0.67945 -0.3048)
			(end -0.67945 0.3048)
			(stroke
				(width 0.1)
				(type default)
			)
			(layer "B.Fab")
		)
		(pad "1" smd circle
			(at 0.40005 0)
			(size 0 0)
			(layers "B.Cu" "B.Mask" "B.Paste")
			(net "FM_SWB_PWRGD_ISO")
		)
		(pad "2" smd circle
			(at -0.40005 0)
			(size 0 0)
			(layers "B.Cu" "B.Mask" "B.Paste")
			(net "FM_SWB_PWRGD_ISO_R")
		)
	)
	(footprint ""
		(layer "B.Cu")
		(at 169.521632 -354.571554 -90)
		(property "Reference" "PR226"
			(at 0 0 90)
			(layer "B.SilkS")
			(hide yes)
			(effects
				(font
					(size 1.27 1.27)
				)
				(justify mirror)
			)
		)
		(property "Value" ""
			(at 0 0 90)
			(layer "B.Fab")
			(effects
				(font
					(size 1.27 1.27)
				)
				(justify mirror)
			)
		)
		(duplicate_pad_numbers_are_jumpers no)
		(fp_line
			(start -0.7874 0.4064)
			(end 0.7874 0.4064)
			(stroke
				(width 0.1524)
				(type default)
			)
			(layer "B.SilkS")
		)
		(fp_line
			(start 0.7874 0.4064)
			(end 0.7874 -0.4064)
			(stroke
				(width 0.1524)
				(type default)
			)
			(layer "B.SilkS")
		)
		(fp_line
			(start -0.7874 -0.4064)
			(end -0.7874 0.4064)
			(stroke
				(width 0.1524)
				(type default)
			)
			(layer "B.SilkS")
		)
		(fp_line
			(start 0.7874 -0.4064)
			(end -0.7874 -0.4064)
			(stroke
				(width 0.1524)
				(type default)
			)
			(layer "B.SilkS")
		)
		(fp_line
			(start -0.67945 0.3048)
			(end -0.120396 0.3048)
			(stroke
				(width 0.1)
				(type default)
			)
			(layer "B.Fab")
		)
		(fp_line
			(start -0.120396 0.3048)
			(end -0.120396 0.2794)
			(stroke
				(width 0.1)
				(type default)
			)
			(layer "B.Fab")
		)
		(fp_line
			(start 0.12065 0.3048)
			(end 0.67945 0.3048)
			(stroke
				(width 0.1)
				(type default)
			)
			(layer "B.Fab")
		)
		(fp_line
			(start 0.67945 0.3048)
			(end 0.67945 -0.305054)
			(stroke
				(width 0.1)
				(type default)
			)
			(layer "B.Fab")
		)
		(fp_line
			(start -0.120396 0.2794)
			(end 0.12065 0.2794)
			(stroke
				(width 0.1)
				(type default)
			)
			(layer "B.Fab")
		)
		(fp_line
			(start 0.12065 0.2794)
			(end 0.12065 0.3048)
			(stroke
				(width 0.1)
				(type default)
			)
			(layer "B.Fab")
		)
		(fp_line
			(start -0.12065 -0.2794)
			(end -0.12065 -0.3048)
			(stroke
				(width 0.1)
				(type default)
			)
			(layer "B.Fab")
		)
		(fp_line
			(start 0.12065 -0.2794)
			(end -0.12065 -0.2794)
			(stroke
				(width 0.1)
				(type default)
			)
			(layer "B.Fab")
		)
		(fp_line
			(start -0.67945 -0.3048)
			(end -0.67945 0.3048)
			(stroke
				(width 0.1)
				(type default)
			)
			(layer "B.Fab")
		)
		(fp_line
			(start -0.12065 -0.3048)
			(end -0.67945 -0.3048)
			(stroke
				(width 0.1)
				(type default)
			)
			(layer "B.Fab")
		)
		(fp_line
			(start 0.12065 -0.305054)
			(end 0.12065 -0.2794)
			(stroke
				(width 0.1)
				(type default)
			)
			(layer "B.Fab")
		)
		(fp_line
			(start 0.67945 -0.305054)
			(end 0.12065 -0.305054)
			(stroke
				(width 0.1)
				(type default)
			)
			(layer "B.Fab")
		)
		(pad "1" smd circle
			(at 0.40005 0 90)
			(size 0 0)
			(layers "B.Cu" "B.Mask" "B.Paste")
			(net "PVCCFA_EHV_FIVRA_CPU1_PVCC1")
		)
		(pad "2" smd circle
			(at -0.40005 0 90)
			(size 0 0)
			(layers "B.Cu" "B.Mask" "B.Paste")
			(net "PVCCFA_EHV_FIVRA_CPU1_VDD1")
		)
	)
)
